(kicad_pcb
	(version 20240108)
	(generator "pcbnew")
	(generator_version "8.0")
	(general
		(thickness 1.62)
		(legacy_teardrops no)
	)
	(paper "A4")
	(title_block
		(title "Jetson Orin Baseboard")
		(date "2025-03-12")
		(rev "1.3.4")
		(company "Antmicro Ltd")
		(comment 1 "www.antmicro.com")
		(comment 9 "footprints 301-304 of 677")
	)
	(layers
		(0 "F.Cu" signal)
		(1 "In1.Cu" signal)
		(2 "In2.Cu" signal)
		(3 "In3.Cu" signal)
		(4 "In4.Cu" jumper)
		(5 "In5.Cu" signal)
		(6 "In6.Cu" signal)
		(31 "B.Cu" signal)
		(32 "B.Adhes" user "B.Adhesive")
		(33 "F.Adhes" user "F.Adhesive")
		(34 "B.Paste" user)
		(35 "F.Paste" user)
		(36 "B.SilkS" user "B.Silkscreen")
		(37 "F.SilkS" user "F.Silkscreen")
		(38 "B.Mask" user)
		(39 "F.Mask" user)
		(40 "Dwgs.User" user "User.Drawings")
		(41 "Cmts.User" user "User.Comments")
		(42 "Eco1.User" user "User.Eco1")
		(43 "Eco2.User" user "User.Eco2")
		(44 "Edge.Cuts" user)
		(45 "Margin" user)
		(46 "B.CrtYd" user "B.Courtyard")
		(47 "F.CrtYd" user "F.Courtyard")
		(48 "B.Fab" user)
		(49 "F.Fab" user)
	)
	(footprint "antmicro-footprints:R_0402_1005Metric"
		(layer "B.Cu")
		(at 73.9 101.95)
		(descr "Resistor SMD 0402")
		(tags "resistor SMD 0402")
		(property "Reference" "R69"
			(at 0.93 -1.54 180)
			(layer "B.SilkS")
			(effects
				(font
					(size 0.7 0.7)
					(thickness 0.15)
				)
				(justify left bottom mirror)
			)
		)
		(property "Value" "R_200R_0402"
			(at 0 -1.4 180)
			(layer "B.Fab")
			(effects
				(font
					(size 0.7 0.7)
					(thickness 0.15)
				)
				(justify left bottom mirror)
			)
		)
		(property "Footprint" "antmicro-footprints:R_0402_1005Metric"
			(at 0 0 0)
			(layer "F.Fab")
			(hide yes)
			(effects
				(font
					(size 1.27 1.27)
					(thickness 0.15)
				)
			)
		)
		(property "Datasheet" "https://www.bourns.com/docs/product-datasheets/cr.pdf"
			(at 0 0 0)
			(layer "F.Fab")
			(hide yes)
			(effects
				(font
					(size 1.27 1.27)
					(thickness 0.15)
				)
			)
		)
		(property "Author" "Antmicro"
			(at 0 0 0)
			(layer "B.Fab")
			(hide yes)
			(effects
				(font
					(size 1 1)
					(thickness 0.15)
				)
				(justify mirror)
			)
		)
		(property "License" "Apache-2.0"
			(at 0 0 0)
			(layer "B.Fab")
			(hide yes)
			(effects
				(font
					(size 1 1)
					(thickness 0.15)
				)
				(justify mirror)
			)
		)
		(property "MPN" "CR0402-FX-2000GLF"
			(at 0 0 0)
			(layer "B.Fab")
			(hide yes)
			(effects
				(font
					(size 1 1)
					(thickness 0.15)
				)
				(justify mirror)
			)
		)
		(property "Manufacturer" "Bourns"
			(at 0 0 0)
			(layer "B.Fab")
			(hide yes)
			(effects
				(font
					(size 1 1)
					(thickness 0.15)
				)
				(justify mirror)
			)
		)
		(property "Tolerance" "1%"
			(at 0 0 0)
			(layer "B.Fab")
			(hide yes)
			(effects
				(font
					(size 1 1)
					(thickness 0.15)
				)
				(justify mirror)
			)
		)
		(property "Val" "200R"
			(at 0 0 0)
			(layer "B.Fab")
			(hide yes)
			(effects
				(font
					(size 1 1)
					(thickness 0.15)
				)
				(justify mirror)
			)
		)
		(sheetname "USB Debug, DP")
		(sheetfile "usb.kicad_sch")
		(attr smd)
		(fp_rect
			(start -0.925 0.47)
			(end 0.925 -0.47)
			(stroke
				(width 0.05)
				(type default)
			)
			(fill none)
			(layer "B.CrtYd")
		)
		(fp_rect
			(start -0.5 0.25)
			(end 0.5 -0.25)
			(stroke
				(width 0.15)
				(type solid)
			)
			(fill none)
			(layer "B.Fab")
		)
		(fp_text user "Author: Antmicro"
			(at -0.95 -4.169 180)
			(layer "B.Fab")
			(hide yes)
			(effects
				(font
					(size 0.7 0.7)
					(thickness 0.15)
				)
				(justify left bottom mirror)
			)
		)
		(fp_text user "${REFERENCE}"
			(at -0.95 -3.168 180)
			(layer "B.Fab")
			(hide yes)
			(effects
				(font
					(size 0.7 0.7)
					(thickness 0.15)
				)
				(justify left bottom mirror)
			)
		)
		(fp_text user "License: Apache-2.0"
			(at -0.95 -5.169 180)
			(layer "B.Fab")
			(hide yes)
			(effects
				(font
					(size 0.7 0.7)
					(thickness 0.15)
				)
				(justify left bottom mirror)
			)
		)
		(pad "1" smd roundrect
			(at -0.48 0)
			(size 0.59 0.64)
			(layers "B.Cu" "B.Paste" "B.Mask")
			(roundrect_rratio 0.25)
			(net 301 "/USB Debug, DP/PDC_GPIO15")
			(pintype "passive")
		)
		(pad "2" smd roundrect
			(at 0.48 0)
			(size 0.59 0.64)
			(layers "B.Cu" "B.Paste" "B.Mask")
			(roundrect_rratio 0.25)
			(net 145 "Net-(D5-A)")
			(pintype "passive")
		)
	)
	(footprint "antmicro-footprints:TSOT23-6"
		(layer "B.Cu")
		(at 133.95 113.95 -90)
		(property "Reference" "U25"
			(at -1.99 -1.11 180)
			(layer "B.SilkS")
			(effects
				(font
					(size 0.7 0.7)
					(thickness 0.15)
				)
				(justify left bottom mirror)
			)
		)
		(property "Value" "AP22615A_TSOT26"
			(at 0 -2.6 90)
			(layer "B.Fab")
			(effects
				(font
					(size 0.7 0.7)
					(thickness 0.15)
				)
				(justify left bottom mirror)
			)
		)
		(property "Footprint" "antmicro-footprints:TSOT23-6"
			(at 0 0 -90)
			(layer "F.Fab")
			(hide yes)
			(effects
				(font
					(size 1.27 1.27)
					(thickness 0.15)
				)
			)
		)
		(property "Datasheet" "https://www.mouser.com/datasheet/2/115/DIOD_S_A0008958405_1-2543193.pdf"
			(at 0 0 -90)
			(layer "F.Fab")
			(hide yes)
			(effects
				(font
					(size 1.27 1.27)
					(thickness 0.15)
				)
			)
		)
		(property "Author" "Antmicro"
			(at 20 247.9 0)
			(layer "B.Fab")
			(hide yes)
			(effects
				(font
					(size 1 1)
					(thickness 0.15)
				)
				(justify mirror)
			)
		)
		(property "License" "Apache-2.0"
			(at 20 247.9 0)
			(layer "B.Fab")
			(hide yes)
			(effects
				(font
					(size 1 1)
					(thickness 0.15)
				)
				(justify mirror)
			)
		)
		(property "MPN" "AP22615AWU-7"
			(at 20 247.9 0)
			(layer "B.Fab")
			(hide yes)
			(effects
				(font
					(size 1 1)
					(thickness 0.15)
				)
				(justify mirror)
			)
		)
		(property "Manufacturer" "Diodes Incorporated"
			(at 20 247.9 0)
			(layer "B.Fab")
			(hide yes)
			(effects
				(font
					(size 1 1)
					(thickness 0.15)
				)
				(justify mirror)
			)
		)
		(sheetname "CSI")
		(sheetfile "csi.kicad_sch")
		(attr smd)
		(fp_line
			(start -1 1.5)
			(end 1 1.497)
			(stroke
				(width 0.15)
				(type solid)
			)
			(layer "B.SilkS")
		)
		(fp_line
			(start -1 1.375)
			(end -1 1.5)
			(stroke
				(width 0.15)
				(type solid)
			)
			(layer "B.SilkS")
		)
		(fp_line
			(start 1 1.375)
			(end 1 1.497)
			(stroke
				(width 0.15)
				(type solid)
			)
			(layer "B.SilkS")
		)
		(fp_line
			(start -1 -1.4)
			(end -1 -1.55)
			(stroke
				(width 0.15)
				(type solid)
			)
			(layer "B.SilkS")
		)
		(fp_line
			(start 1 -1.4)
			(end 1 -1.55)
			(stroke
				(width 0.15)
				(type solid)
			)
			(layer "B.SilkS")
		)
		(fp_line
			(start -1 -1.55)
			(end 1 -1.55)
			(stroke
				(width 0.15)
				(type solid)
			)
			(layer "B.SilkS")
		)
		(fp_circle
			(center -1.44 1.5)
			(end -1.39 1.5)
			(stroke
				(width 0.15)
				(type solid)
			)
			(fill solid)
			(layer "B.SilkS")
		)
		(fp_rect
			(start 1.93 1.7)
			(end -1.93 -1.7)
			(stroke
				(width 0.05)
				(type solid)
			)
			(fill none)
			(layer "B.CrtYd")
		)
		(fp_line
			(start -0.876 1.096)
			(end -0.45 1.521)
			(stroke
				(width 0.15)
				(type solid)
			)
			(layer "B.Fab")
		)
		(fp_rect
			(start 0.875 -1.528)
			(end -0.875 1.525)
			(stroke
				(width 0.15)
				(type solid)
			)
			(fill none)
			(layer "B.Fab")
		)
		(fp_text user "${REFERENCE}"
			(at -1.93 -3.8 90)
			(layer "B.Fab")
			(hide yes)
			(effects
				(font
					(size 0.7 0.7)
					(thickness 0.15)
				)
				(justify left bottom mirror)
			)
		)
		(fp_text user "Author: Antmicro"
			(at -1.93 -5 90)
			(layer "B.Fab")
			(hide yes)
			(effects
				(font
					(size 0.7 0.7)
					(thickness 0.15)
				)
				(justify left bottom mirror)
			)
		)
		(fp_text user "License: Apache-2.0"
			(at -1.93 -6.199 90)
			(layer "B.Fab")
			(hide yes)
			(effects
				(font
					(size 0.7 0.7)
					(thickness 0.15)
				)
				(justify left bottom mirror)
			)
		)
		(pad "1" smd rect
			(at -1.301 0.947)
			(size 0.7 1.2)
			(layers "B.Cu" "B.Paste" "B.Mask")
			(net 108 "/CSI/CSIA_3V3")
			(pinfunction "OUT")
			(pintype "power_out")
		)
		(pad "2" smd rect
			(at -1.301 -0.004)
			(size 0.7 1.2)
			(layers "B.Cu" "B.Paste" "B.Mask")
			(net 1 "GND")
			(pinfunction "GND")
			(pintype "power_in")
		)
		(pad "3" smd rect
			(at -1.301 -0.954)
			(size 0.7 1.2)
			(layers "B.Cu" "B.Paste" "B.Mask")
			(net 311 "CSIA_FLG")
			(pinfunction "FLG")
			(pintype "output")
		)
		(pad "4" smd rect
			(at 1.299 -0.954)
			(size 0.7 1.2)
			(layers "B.Cu" "B.Paste" "B.Mask")
			(net 322 "CSIA_PEN")
			(pinfunction "EN")
			(pintype "input")
		)
		(pad "5" smd rect
			(at 1.299 -0.004)
			(size 0.7 1.2)
			(layers "B.Cu" "B.Paste" "B.Mask")
			(net 335 "/CSI/CSIA_3V3_ISET")
			(pinfunction "ISET")
			(pintype "passive")
		)
		(pad "6" smd rect
			(at 1.299 0.947)
			(size 0.7 1.2)
			(layers "B.Cu" "B.Paste" "B.Mask")
			(net 87 "+3V3")
			(pinfunction "IN")
			(pintype "power_in")
		)
	)
	(footprint "antmicro-footprints:R_0402_1005Metric"
		(layer "B.Cu")
		(at 91.81 100.59 -135)
		(descr "Resistor SMD 0402")
		(tags "resistor SMD 0402")
		(property "Reference" "R212"
			(at -1.435427 -1.308148 45)
			(layer "B.SilkS")
			(effects
				(font
					(size 0.7 0.7)
					(thickness 0.15)
				)
				(justify left bottom mirror)
			)
		)
		(property "Value" "R_499R_0402"
			(at -1.011843 -1.772046 45)
			(layer "B.Fab")
			(effects
				(font
					(size 0.7 0.7)
					(thickness 0.15)
				)
				(justify left bottom mirror)
			)
		)
		(property "Footprint" "antmicro-footprints:R_0402_1005Metric"
			(at 0 0 -135)
			(layer "F.Fab")
			(hide yes)
			(effects
				(font
					(size 1.27 1.27)
					(thickness 0.15)
				)
			)
		)
		(property "Datasheet" "https://www.mouser.com/datasheet/2/54/cr-1858361.pdf"
			(at 0 0 -135)
			(layer "F.Fab")
			(hide yes)
			(effects
				(font
					(size 1.27 1.27)
					(thickness 0.15)
				)
			)
		)
		(property "Author" "Antmicro"
			(at 85.601602 236.637345 0)
			(layer "B.Fab")
			(hide yes)
			(effects
				(font
					(size 1 1)
					(thickness 0.15)
				)
				(justify mirror)
			)
		)
		(property "License" "Apache-2.0"
			(at 85.601602 236.637345 0)
			(layer "B.Fab")
			(hide yes)
			(effects
				(font
					(size 1 1)
					(thickness 0.15)
				)
				(justify mirror)
			)
		)
		(property "MPN" "CR0402-FX-4990GLF"
			(at 85.601602 236.637345 0)
			(layer "B.Fab")
			(hide yes)
			(effects
				(font
					(size 1 1)
					(thickness 0.15)
				)
				(justify mirror)
			)
		)
		(property "Manufacturer" "Bourns"
			(at 85.601602 236.637345 0)
			(layer "B.Fab")
			(hide yes)
			(effects
				(font
					(size 1 1)
					(thickness 0.15)
				)
				(justify mirror)
			)
		)
		(property "Tolerance" "1%"
			(at 85.601602 236.637345 0)
			(layer "B.Fab")
			(hide yes)
			(effects
				(font
					(size 1 1)
					(thickness 0.15)
				)
				(justify mirror)
			)
		)
		(property "Val" "499R"
			(at 85.601602 236.637345 0)
			(layer "B.Fab")
			(hide yes)
			(effects
				(font
					(size 1 1)
					(thickness 0.15)
				)
				(justify mirror)
			)
		)
		(sheetname "HDMI")
		(sheetfile "hdmi.kicad_sch")
		(attr smd)
		(fp_poly
			(pts
				(xy -0.925 0.47) (xy 0.925 0.47) (xy 0.925 -0.47) (xy -0.925 -0.47)
			)
			(stroke
				(width 0.05)
				(type default)
			)
			(fill none)
			(layer "B.CrtYd")
		)
		(fp_poly
			(pts
				(xy -0.5 0.25) (xy 0.5 0.25) (xy 0.5 -0.25) (xy -0.5 -0.25)
			)
			(stroke
				(width 0.15)
				(type solid)
			)
			(fill none)
			(layer "B.Fab")
		)
		(fp_text user "Author: Antmicro"
			(at -0.95 -4.169 45)
			(layer "B.Fab")
			(hide yes)
			(effects
				(font
					(size 0.7 0.7)
					(thickness 0.15)
				)
				(justify left bottom mirror)
			)
		)
		(fp_text user "License: Apache-2.0"
			(at -0.949999 -5.169 45)
			(layer "B.Fab")
			(hide yes)
			(effects
				(font
					(size 0.7 0.7)
					(thickness 0.15)
				)
				(justify left bottom mirror)
			)
		)
		(fp_text user "${REFERENCE}"
			(at -0.95 -3.168 45)
			(layer "B.Fab")
			(hide yes)
			(effects
				(font
					(size 0.7 0.7)
					(thickness 0.15)
				)
				(justify left bottom mirror)
			)
		)
		(pad "1" smd roundrect
			(at -0.48 0 225)
			(size 0.59 0.64)
			(layers "B.Cu" "B.Paste" "B.Mask")
			(roundrect_rratio 0.25)
			(net 623 "Net-(Q2-D)")
			(pintype "passive")
		)
		(pad "2" smd roundrect
			(at 0.48 0 225)
			(size 0.59 0.64)
			(layers "B.Cu" "B.Paste" "B.Mask")
			(roundrect_rratio 0.25)
			(net 487 "/HDMI/HDMI_D1_N")
			(pintype "passive")
		)
	)
	(footprint "antmicro-footprints:C_0402_1005Metric"
		(layer "B.Cu")
		(at 65.3 76.5 180)
		(descr "Capacitor SMD 0402")
		(tags "capacitor SMD 0402")
		(property "Reference" "C118"
			(at -16.91 -3.45 0)
			(layer "B.SilkS")
			(effects
				(font
					(size 0.7 0.7)
					(thickness 0.15)
				)
				(justify left bottom mirror)
			)
		)
		(property "Value" "C_100n_0402"
			(at 0 -1.4 0)
			(layer "B.Fab")
			(effects
				(font
					(size 0.7 0.7)
					(thickness 0.15)
				)
				(justify left bottom mirror)
			)
		)
		(property "Footprint" "antmicro-footprints:C_0402_1005Metric"
			(at 0 0 180)
			(layer "F.Fab")
			(hide yes)
			(effects
				(font
					(size 1.27 1.27)
					(thickness 0.15)
				)
			)
		)
		(property "Datasheet" "https://www.murata.com/products/productdetail?partno=GRM155R61H104KE14%23"
			(at 0 0 180)
			(layer "F.Fab")
			(hide yes)
			(effects
				(font
					(size 1.27 1.27)
					(thickness 0.15)
				)
			)
		)
		(property "Author" "Antmicro"
			(at 130.6 153 0)
			(layer "B.Fab")
			(hide yes)
			(effects
				(font
					(size 1 1)
					(thickness 0.15)
				)
				(justify mirror)
			)
		)
		(property "Dielectric" "X5R"
			(at 130.6 153 0)
			(layer "B.Fab")
			(hide yes)
			(effects
				(font
					(size 1 1)
					(thickness 0.15)
				)
				(justify mirror)
			)
		)
		(property "License" "Apache-2.0"
			(at 130.6 153 0)
			(layer "B.Fab")
			(hide yes)
			(effects
				(font
					(size 1 1)
					(thickness 0.15)
				)
				(justify mirror)
			)
		)
		(property "MPN" "GRM155R61H104KE14D"
			(at 130.6 153 0)
			(layer "B.Fab")
			(hide yes)
			(effects
				(font
					(size 1 1)
					(thickness 0.15)
				)
				(justify mirror)
			)
		)
		(property "Manufacturer" "Murata"
			(at 130.6 153 0)
			(layer "B.Fab")
			(hide yes)
			(effects
				(font
					(size 1 1)
					(thickness 0.15)
				)
				(justify mirror)
			)
		)
		(property "Val" "100n"
			(at 130.6 153 0)
			(layer "B.Fab")
			(hide yes)
			(effects
				(font
					(size 1 1)
					(thickness 0.15)
				)
				(justify mirror)
			)
		)
		(property "Voltage" "50V"
			(at 130.6 153 0)
			(layer "B.Fab")
			(hide yes)
			(effects
				(font
					(size 1 1)
					(thickness 0.15)
				)
				(justify mirror)
			)
		)
		(sheetname "Supply")
		(sheetfile "supply.kicad_sch")
		(attr smd)
		(fp_rect
			(start -0.925 0.47)
			(end 0.925 -0.47)
			(stroke
				(width 0.05)
				(type default)
			)
			(fill none)
			(layer "B.CrtYd")
		)
		(fp_line
			(start 0.504 0.25)
			(end -0.494 0.25)
			(stroke
				(width 0.15)
				(type solid)
			)
			(layer "B.Fab")
		)
		(fp_line
			(start 0.504 -0.248)
			(end 0.504 0.25)
			(stroke
				(width 0.15)
				(type solid)
			)
			(layer "B.Fab")
		)
		(fp_line
			(start -0.494 0.25)
			(end -0.494 -0.248)
			(stroke
				(width 0.15)
				(type solid)
			)
			(layer "B.Fab")
		)
		(fp_line
			(start -0.494 -0.248)
			(end 0.504 -0.248)
			(stroke
				(width 0.15)
				(type solid)
			)
			(layer "B.Fab")
		)
		(fp_text user "License: Apache-2.0"
			(at -0.932 -5.17 0)
			(layer "B.Fab")
			(hide yes)
			(effects
				(font
					(size 0.7 0.7)
					(thickness 0.15)
				)
				(justify left bottom mirror)
			)
		)
		(fp_text user "Author: Antmicro"
			(at -0.932 -4.17 0)
			(layer "B.Fab")
			(hide yes)
			(effects
				(font
					(size 0.7 0.7)
					(thickness 0.15)
				)
				(justify left bottom mirror)
			)
		)
		(fp_text user "${REFERENCE}"
			(at -0.932 -3.168 0)
			(layer "B.Fab")
			(hide yes)
			(effects
				(font
					(size 0.7 0.7)
					(thickness 0.15)
				)
				(justify left bottom mirror)
			)
		)
		(pad "1" smd roundrect
			(at -0.48 0 180)
			(size 0.59 0.64)
			(layers "B.Cu" "B.Paste" "B.Mask")
			(roundrect_rratio 0.25)
			(net 1 "GND")
			(pintype "passive")
		)
		(pad "2" smd roundrect
			(at 0.48 0 180)
			(size 0.59 0.64)
			(layers "B.Cu" "B.Paste" "B.Mask")
			(roundrect_rratio 0.25)
			(net 117 "3V3_STDB")
			(pintype "passive")
		)
	)
)
